(kicad_pcb
	(version 20260206)
	(generator "pcbnew")
	(generator_version "10.0")
	(general
		(thickness 1.6)
		(legacy_teardrops no)
	)
	(paper "A4")
	(title_block
		(title "pdpb — Lightning_PDPB_BRD.brd")
		(comment 1 "Lightning (Wiwynn / Facebook NVMe JBOF) / footprints 331-338 of 1140")
	)
	(layers
		(0 "F.Cu" signal "TOP")
		(4 "In1.Cu" signal "L2GND")
		(6 "In2.Cu" signal "L3")
		(8 "In3.Cu" signal "L4VCC")
		(10 "In4.Cu" signal "L5VCC")
		(12 "In5.Cu" signal "L6")
		(14 "In6.Cu" signal "L7GND")
		(2 "B.Cu" signal "BOTTOM")
		(9 "F.Adhes" user "F.Adhesive")
		(11 "B.Adhes" user "B.Adhesive")
		(13 "F.Paste" user "Package Geometry/Pastemask Top")
		(15 "B.Paste" user "Package Geometry/Pastemask Bottom")
		(5 "F.SilkS" user "Ref Des/Silkscreen Top")
		(7 "B.SilkS" user "Ref Des/Silkscreen Bottom")
		(1 "F.Mask" user "Board Geometry/Soldermask Top")
		(3 "B.Mask" user "Board Geometry/Soldermask Bottom")
		(17 "Dwgs.User" user "User.Drawings")
		(19 "Cmts.User" user "User.Comments")
		(21 "Eco1.User" user "User.Eco1")
		(23 "Eco2.User" user "User.Eco2")
		(25 "Edge.Cuts" user "Board Geometry/Outline")
		(27 "Margin" user)
		(31 "F.CrtYd" user "Package Geometry/Place Bound Top")
		(29 "B.CrtYd" user "Package Geometry/Place Bound Bottom")
		(35 "F.Fab" user "Ref Des/Assembly Top")
		(33 "B.Fab" user "Ref Des/Assembly Bottom")
	)
	(footprint ""
		(layer "F.Cu")
		(at 24.8158 -294.7416 -90)
		(property "Reference" "R145"
			(at 0 0 270)
			(layer "F.SilkS")
			(hide yes)
			(effects
				(font
					(size 1.27 1.27)
				)
			)
		)
		(property "Value" "4K7R2J-2-GP"
			(at 0.064008 -3.993896 270)
			(unlocked yes)
			(layer "F.Fab")
			(hide yes)
			(effects
				(font
					(size 1.016 1.016)
					(thickness 0.1524)
				)
			)
		)
		(property "Device Type" "R402H16"
			(at 0.064008 -5.517896 270)
			(unlocked yes)
			(layer "F.Fab")
			(hide yes)
			(effects
				(font
					(size 1.016 1.016)
					(thickness 0.1524)
				)
			)
		)
		(duplicate_pad_numbers_are_jumpers no)
		(fp_line
			(start -0.508 -0.9398)
			(end -0.508 0.9398)
			(stroke
				(width 0.1524)
				(type default)
			)
			(layer "F.SilkS")
		)
		(fp_line
			(start 0.508 -0.9398)
			(end -0.508 -0.9398)
			(stroke
				(width 0.1524)
				(type default)
			)
			(layer "F.SilkS")
		)
		(fp_rect
			(start -0.508 0.9398)
			(end 0.508 -0.9398)
			(stroke
				(width 0)
				(type default)
			)
			(fill no)
			(layer "F.CrtYd")
		)
		(fp_rect
			(start -0.508 0.9398)
			(end 0.508 -0.9398)
			(stroke
				(width 0)
				(type default)
			)
			(fill no)
			(layer "F.Fab")
		)
		(pad "1" smd custom
			(at 0 -0.4445 270)
			(size 0.1397 0.1397)
			(layers "F.Cu" "F.Mask" "F.Paste")
			(net "P12V")
			(options
				(clearance outline)
				(anchor circle)
			)
			(primitives
				(gr_poly
					(pts
						(arc
							(start -0.1778 -0.2794)
							(mid -0.249642 -0.249642)
							(end -0.2794 -0.1778)
						)
						(arc
							(start -0.2794 0.1778)
							(mid -0.249642 0.249642)
							(end -0.1778 0.2794)
						)
						(arc
							(start 0.1778 0.2794)
							(mid 0.249642 0.249642)
							(end 0.2794 0.1778)
						)
						(arc
							(start 0.2794 -0.1778)
							(mid 0.249642 -0.249642)
							(end 0.1778 -0.2794)
						)
					)
					(width 0)
					(fill yes)
				)
			)
		)
		(pad "2" smd custom
			(at 0 0.4445 270)
			(size 0.1397 0.1397)
			(layers "F.Cu" "F.Mask" "F.Paste")
			(net "SW_SSD7_R")
			(options
				(clearance outline)
				(anchor circle)
			)
			(primitives
				(gr_poly
					(pts
						(arc
							(start -0.1778 -0.2794)
							(mid -0.249642 -0.249642)
							(end -0.2794 -0.1778)
						)
						(arc
							(start -0.2794 0.1778)
							(mid -0.249642 0.249642)
							(end -0.1778 0.2794)
						)
						(arc
							(start 0.1778 0.2794)
							(mid 0.249642 0.249642)
							(end 0.2794 0.1778)
						)
						(arc
							(start 0.2794 -0.1778)
							(mid 0.249642 -0.249642)
							(end 0.1778 -0.2794)
						)
					)
					(width 0)
					(fill yes)
				)
			)
		)
	)
	(footprint ""
		(layer "F.Cu")
		(at 24.9936 -111.0996 180)
		(property "Reference" "PC1213"
			(at 0 0 180)
			(layer "F.SilkS")
			(hide yes)
			(effects
				(font
					(size 1.27 1.27)
				)
			)
		)
		(property "Value" "SCD01U50V2KX-1GP"
			(at 1.1811 -2.7051 180)
			(unlocked yes)
			(layer "F.Fab")
			(hide yes)
			(effects
				(font
					(size 1.016 1.016)
					(thickness 0.1524)
				)
			)
		)
		(property "Device Type" "C402H22"
			(at 1.1811 -4.2291 180)
			(unlocked yes)
			(layer "F.Fab")
			(hide yes)
			(effects
				(font
					(size 1.016 1.016)
					(thickness 0.1524)
				)
			)
		)
		(duplicate_pad_numbers_are_jumpers no)
		(fp_rect
			(start -0.4318 0.9525)
			(end 0.4318 -0.9525)
			(stroke
				(width 0)
				(type default)
			)
			(fill no)
			(layer "F.CrtYd")
		)
		(fp_rect
			(start -0.4318 0.9525)
			(end 0.4318 -0.9525)
			(stroke
				(width 0)
				(type default)
			)
			(fill no)
			(layer "F.Fab")
		)
		(pad "1" smd custom
			(at 0 -0.4445 180)
			(size 0.1524 0.1524)
			(layers "F.Cu" "F.Mask" "F.Paste")
			(net "P12V_SSD13")
			(options
				(clearance outline)
				(anchor circle)
			)
			(primitives
				(gr_poly
					(pts
						(arc
							(start 0.3048 -0.2032)
							(mid 0.275042 -0.275042)
							(end 0.2032 -0.3048)
						)
						(arc
							(start -0.2032 -0.3048)
							(mid -0.275042 -0.275042)
							(end -0.3048 -0.2032)
						)
						(arc
							(start -0.3048 0.2032)
							(mid -0.275042 0.275042)
							(end -0.2032 0.3048)
						)
						(arc
							(start 0.2032 0.3048)
							(mid 0.275042 0.275042)
							(end 0.3048 0.2032)
						)
					)
					(width 0)
					(fill yes)
				)
			)
		)
		(pad "2" smd custom
			(at 0 0.4445 180)
			(size 0.1524 0.1524)
			(layers "F.Cu" "F.Mask" "F.Paste")
			(net "GND")
			(options
				(clearance outline)
				(anchor circle)
			)
			(primitives
				(gr_poly
					(pts
						(arc
							(start 0.3048 -0.2032)
							(mid 0.275042 -0.275042)
							(end 0.2032 -0.3048)
						)
						(arc
							(start -0.2032 -0.3048)
							(mid -0.275042 -0.275042)
							(end -0.3048 -0.2032)
						)
						(arc
							(start -0.3048 0.2032)
							(mid -0.275042 0.275042)
							(end -0.2032 0.3048)
						)
						(arc
							(start 0.2032 0.3048)
							(mid 0.275042 0.275042)
							(end 0.3048 0.2032)
						)
					)
					(width 0)
					(fill yes)
				)
			)
		)
	)
	(footprint ""
		(layer "F.Cu")
		(at 215.011 -498.983 180)
		(property "Reference" "PC1187"
			(at 0 0 180)
			(layer "F.SilkS")
			(hide yes)
			(effects
				(font
					(size 1.27 1.27)
				)
			)
		)
		(property "Value" "SCD1U50V3KX-GP"
			(at 0 -2.8194 180)
			(unlocked yes)
			(layer "F.Fab")
			(hide yes)
			(effects
				(font
					(size 1.016 1.016)
					(thickness 0.1524)
				)
			)
		)
		(property "Device Type" "C603H36"
			(at 0 -4.3434 180)
			(unlocked yes)
			(layer "F.Fab")
			(hide yes)
			(effects
				(font
					(size 1.016 1.016)
					(thickness 0.1524)
				)
			)
		)
		(duplicate_pad_numbers_are_jumpers no)
		(fp_line
			(start 0.508 0)
			(end -0.508 0)
			(stroke
				(width 0.2032)
				(type default)
			)
			(layer "F.SilkS")
		)
		(fp_rect
			(start -0.5842 1.3335)
			(end 0.5842 -1.3335)
			(stroke
				(width 0)
				(type default)
			)
			(fill no)
			(layer "F.CrtYd")
		)
		(fp_rect
			(start -0.5842 1.3335)
			(end 0.5842 -1.3335)
			(stroke
				(width 0)
				(type default)
			)
			(fill no)
			(layer "F.Fab")
		)
		(pad "1" smd custom
			(at 0 -0.762 180)
			(size 0.2159 0.2159)
			(layers "F.Cu" "F.Mask" "F.Paste")
			(net "P12V_SSD0")
			(options
				(clearance outline)
				(anchor circle)
			)
			(primitives
				(gr_poly
					(pts
						(arc
							(start -0.3302 -0.4318)
							(mid -0.402042 -0.402042)
							(end -0.4318 -0.3302)
						)
						(arc
							(start -0.4318 0.3302)
							(mid -0.402042 0.402042)
							(end -0.3302 0.4318)
						)
						(arc
							(start 0.3302 0.4318)
							(mid 0.402042 0.402042)
							(end 0.4318 0.3302)
						)
						(arc
							(start 0.4318 -0.3302)
							(mid 0.402042 -0.402042)
							(end 0.3302 -0.4318)
						)
					)
					(width 0)
					(fill yes)
				)
			)
		)
		(pad "2" smd custom
			(at 0 0.762 180)
			(size 0.2159 0.2159)
			(layers "F.Cu" "F.Mask" "F.Paste")
			(net "GND")
			(options
				(clearance outline)
				(anchor circle)
			)
			(primitives
				(gr_poly
					(pts
						(arc
							(start -0.3302 -0.4318)
							(mid -0.402042 -0.402042)
							(end -0.4318 -0.3302)
						)
						(arc
							(start -0.4318 0.3302)
							(mid -0.402042 0.402042)
							(end -0.3302 0.4318)
						)
						(arc
							(start 0.3302 0.4318)
							(mid 0.402042 0.402042)
							(end 0.4318 0.3302)
						)
						(arc
							(start 0.4318 -0.3302)
							(mid 0.402042 -0.402042)
							(end 0.3302 -0.4318)
						)
					)
					(width 0)
					(fill yes)
				)
			)
		)
	)
	(footprint ""
		(layer "F.Cu")
		(at 219.075 -499.237)
		(property "Reference" "R9239"
			(at 0 0 0)
			(layer "F.SilkS")
			(hide yes)
			(effects
				(font
					(size 1.27 1.27)
				)
			)
		)
		(property "Value" "2R2010F-GP"
			(at 0.0762 -4.5466 0)
			(unlocked yes)
			(layer "F.Fab")
			(hide yes)
			(effects
				(font
					(size 1.016 1.016)
					(thickness 0.1524)
				)
			)
		)
		(property "Device Type" "R2010H26"
			(at 0.0762 -6.1468 0)
			(unlocked yes)
			(layer "F.Fab")
			(hide yes)
			(effects
				(font
					(size 1.016 1.016)
					(thickness 0.1524)
				)
			)
		)
		(duplicate_pad_numbers_are_jumpers no)
		(fp_line
			(start -3.302 -1.651)
			(end -3.302 1.651)
			(stroke
				(width 0.1524)
				(type default)
			)
			(layer "F.SilkS")
		)
		(fp_line
			(start -3.302 1.651)
			(end 3.302 1.651)
			(stroke
				(width 0.1524)
				(type default)
			)
			(layer "F.SilkS")
		)
		(fp_line
			(start 3.302 -1.651)
			(end -3.302 -1.651)
			(stroke
				(width 0.1524)
				(type default)
			)
			(layer "F.SilkS")
		)
		(fp_line
			(start 3.302 1.651)
			(end 3.302 -1.651)
			(stroke
				(width 0.1524)
				(type default)
			)
			(layer "F.SilkS")
		)
		(fp_rect
			(start -3.3782 1.7272)
			(end 3.3782 -1.7272)
			(stroke
				(width 0)
				(type default)
			)
			(fill no)
			(layer "F.CrtYd")
		)
		(fp_poly
			(pts
				(xy 3.3782 -1.7272) (xy -3.3782 -1.7272) (xy -3.3782 1.7272) (xy 3.3782 1.7272)
			)
			(stroke
				(width 0)
				(type default)
			)
			(fill no)
			(layer "F.Fab")
		)
		(pad "1" smd rect
			(at -2.3495 0)
			(size 1.143 2.794)
			(layers "F.Cu" "F.Mask" "F.Paste")
			(net "P12V_SSD0")
		)
		(pad "2" smd rect
			(at 2.3495 0)
			(size 1.143 2.794)
			(layers "F.Cu" "F.Mask" "F.Paste")
			(net "12V_PRECH_SSD0")
		)
	)
	(footprint ""
		(layer "F.Cu")
		(at 209.804 -191.643 -90)
		(property "Reference" "R141"
			(at 0 0 270)
			(layer "F.SilkS")
			(hide yes)
			(effects
				(font
					(size 1.27 1.27)
				)
			)
		)
		(property "Value" "4K7R2J-2-GP"
			(at 0.064008 -3.993896 270)
			(unlocked yes)
			(layer "F.Fab")
			(hide yes)
			(effects
				(font
					(size 1.016 1.016)
					(thickness 0.1524)
				)
			)
		)
		(property "Device Type" "R402H16"
			(at 0.064008 -5.517896 270)
			(unlocked yes)
			(layer "F.Fab")
			(hide yes)
			(effects
				(font
					(size 1.016 1.016)
					(thickness 0.1524)
				)
			)
		)
		(duplicate_pad_numbers_are_jumpers no)
		(fp_line
			(start -0.508 -0.9398)
			(end -0.508 0.9398)
			(stroke
				(width 0.1524)
				(type default)
			)
			(layer "F.SilkS")
		)
		(fp_line
			(start 0.508 -0.9398)
			(end -0.508 -0.9398)
			(stroke
				(width 0.1524)
				(type default)
			)
			(layer "F.SilkS")
		)
		(fp_rect
			(start -0.508 0.9398)
			(end 0.508 -0.9398)
			(stroke
				(width 0)
				(type default)
			)
			(fill no)
			(layer "F.CrtYd")
		)
		(fp_rect
			(start -0.508 0.9398)
			(end 0.508 -0.9398)
			(stroke
				(width 0)
				(type default)
			)
			(fill no)
			(layer "F.Fab")
		)
		(pad "1" smd custom
			(at 0 -0.4445 270)
			(size 0.1397 0.1397)
			(layers "F.Cu" "F.Mask" "F.Paste")
			(net "P12V")
			(options
				(clearance outline)
				(anchor circle)
			)
			(primitives
				(gr_poly
					(pts
						(arc
							(start -0.1778 -0.2794)
							(mid -0.249642 -0.249642)
							(end -0.2794 -0.1778)
						)
						(arc
							(start -0.2794 0.1778)
							(mid -0.249642 0.249642)
							(end -0.1778 0.2794)
						)
						(arc
							(start 0.1778 0.2794)
							(mid 0.249642 0.249642)
							(end 0.2794 0.1778)
						)
						(arc
							(start 0.2794 -0.1778)
							(mid 0.249642 -0.249642)
							(end 0.1778 -0.2794)
						)
					)
					(width 0)
					(fill yes)
				)
			)
		)
		(pad "2" smd custom
			(at 0 0.4445 270)
			(size 0.1397 0.1397)
			(layers "F.Cu" "F.Mask" "F.Paste")
			(net "SW_SSD3_R")
			(options
				(clearance outline)
				(anchor circle)
			)
			(primitives
				(gr_poly
					(pts
						(arc
							(start -0.1778 -0.2794)
							(mid -0.249642 -0.249642)
							(end -0.2794 -0.1778)
						)
						(arc
							(start -0.2794 0.1778)
							(mid -0.249642 0.249642)
							(end -0.1778 0.2794)
						)
						(arc
							(start 0.1778 0.2794)
							(mid 0.249642 0.249642)
							(end 0.2794 0.1778)
						)
						(arc
							(start 0.2794 -0.1778)
							(mid 0.249642 -0.249642)
							(end 0.1778 -0.2794)
						)
					)
					(width 0)
					(fill yes)
				)
			)
		)
	)
	(footprint ""
		(layer "F.Cu")
		(at 90.297 -313.817 180)
		(property "Reference" "R9079"
			(at 0 0 180)
			(layer "F.SilkS")
			(hide yes)
			(effects
				(font
					(size 1.27 1.27)
				)
			)
		)
		(property "Value" "27R2F-GP"
			(at 0.064008 -3.993896 180)
			(unlocked yes)
			(layer "F.Fab")
			(hide yes)
			(effects
				(font
					(size 1.016 1.016)
					(thickness 0.1524)
				)
			)
		)
		(property "Device Type" "R402H16"
			(at 0.064008 -5.517896 180)
			(unlocked yes)
			(layer "F.Fab")
			(hide yes)
			(effects
				(font
					(size 1.016 1.016)
					(thickness 0.1524)
				)
			)
		)
		(duplicate_pad_numbers_are_jumpers no)
		(fp_line
			(start 0.508 -0.9398)
			(end -0.508 -0.9398)
			(stroke
				(width 0.1524)
				(type default)
			)
			(layer "F.SilkS")
		)
		(fp_line
			(start -0.508 -0.9398)
			(end -0.508 0.9398)
			(stroke
				(width 0.1524)
				(type default)
			)
			(layer "F.SilkS")
		)
		(fp_rect
			(start -0.508 0.9398)
			(end 0.508 -0.9398)
			(stroke
				(width 0)
				(type default)
			)
			(fill no)
			(layer "F.CrtYd")
		)
		(fp_rect
			(start -0.508 0.9398)
			(end 0.508 -0.9398)
			(stroke
				(width 0)
				(type default)
			)
			(fill no)
			(layer "F.Fab")
		)
		(pad "1" smd custom
			(at 0 -0.4445 180)
			(size 0.1397 0.1397)
			(layers "F.Cu" "F.Mask" "F.Paste")
			(net "PE_CLK_100M_DR11_2_R_N")
			(options
				(clearance outline)
				(anchor circle)
			)
			(primitives
				(gr_poly
					(pts
						(arc
							(start -0.1778 -0.2794)
							(mid -0.249642 -0.249642)
							(end -0.2794 -0.1778)
						)
						(arc
							(start -0.2794 0.1778)
							(mid -0.249642 0.249642)
							(end -0.1778 0.2794)
						)
						(arc
							(start 0.1778 0.2794)
							(mid 0.249642 0.249642)
							(end 0.2794 0.1778)
						)
						(arc
							(start 0.2794 -0.1778)
							(mid 0.249642 -0.249642)
							(end 0.1778 -0.2794)
						)
					)
					(width 0)
					(fill yes)
				)
			)
		)
		(pad "2" smd custom
			(at 0 0.4445 180)
			(size 0.1397 0.1397)
			(layers "F.Cu" "F.Mask" "F.Paste")
			(net "PE_CLK100M_DR11_2_N")
			(options
				(clearance outline)
				(anchor circle)
			)
			(primitives
				(gr_poly
					(pts
						(arc
							(start -0.1778 -0.2794)
							(mid -0.249642 -0.249642)
							(end -0.2794 -0.1778)
						)
						(arc
							(start -0.2794 0.1778)
							(mid -0.249642 0.249642)
							(end -0.1778 0.2794)
						)
						(arc
							(start 0.1778 0.2794)
							(mid 0.249642 0.249642)
							(end 0.2794 0.1778)
						)
						(arc
							(start 0.2794 -0.1778)
							(mid 0.249642 -0.249642)
							(end 0.1778 -0.2794)
						)
					)
					(width 0)
					(fill yes)
				)
			)
		)
	)
	(footprint ""
		(layer "F.Cu")
		(at 24.003 -197.231)
		(property "Reference" "R9768"
			(at 0 0 0)
			(layer "F.SilkS")
			(hide yes)
			(effects
				(font
					(size 1.27 1.27)
				)
			)
		)
		(property "Value" "4K7R2J-2-GP"
			(at 0.064008 -3.993896 0)
			(unlocked yes)
			(layer "F.Fab")
			(hide yes)
			(effects
				(font
					(size 1.016 1.016)
					(thickness 0.1524)
				)
			)
		)
		(property "Device Type" "R402H16"
			(at 0.064008 -5.517896 0)
			(unlocked yes)
			(layer "F.Fab")
			(hide yes)
			(effects
				(font
					(size 1.016 1.016)
					(thickness 0.1524)
				)
			)
		)
		(duplicate_pad_numbers_are_jumpers no)
		(fp_line
			(start -0.508 -0.9398)
			(end -0.508 0.9398)
			(stroke
				(width 0.1524)
				(type default)
			)
			(layer "F.SilkS")
		)
		(fp_line
			(start 0.508 -0.9398)
			(end -0.508 -0.9398)
			(stroke
				(width 0.1524)
				(type default)
			)
			(layer "F.SilkS")
		)
		(fp_rect
			(start -0.508 0.9398)
			(end 0.508 -0.9398)
			(stroke
				(width 0)
				(type default)
			)
			(fill no)
			(layer "F.CrtYd")
		)
		(fp_rect
			(start -0.508 0.9398)
			(end 0.508 -0.9398)
			(stroke
				(width 0)
				(type default)
			)
			(fill no)
			(layer "F.Fab")
		)
		(pad "1" smd custom
			(at 0 -0.4445)
			(size 0.1397 0.1397)
			(layers "F.Cu" "F.Mask" "F.Paste")
			(net "SSD8_PWREN")
			(options
				(clearance outline)
				(anchor circle)
			)
			(primitives
				(gr_poly
					(pts
						(arc
							(start -0.1778 -0.2794)
							(mid -0.249642 -0.249642)
							(end -0.2794 -0.1778)
						)
						(arc
							(start -0.2794 0.1778)
							(mid -0.249642 0.249642)
							(end -0.1778 0.2794)
						)
						(arc
							(start 0.1778 0.2794)
							(mid 0.249642 0.249642)
							(end 0.2794 0.1778)
						)
						(arc
							(start 0.2794 -0.1778)
							(mid 0.249642 -0.249642)
							(end 0.1778 -0.2794)
						)
					)
					(width 0)
					(fill yes)
				)
			)
		)
		(pad "2" smd custom
			(at 0 0.4445)
			(size 0.1397 0.1397)
			(layers "F.Cu" "F.Mask" "F.Paste")
			(net "GND")
			(options
				(clearance outline)
				(anchor circle)
			)
			(primitives
				(gr_poly
					(pts
						(arc
							(start -0.1778 -0.2794)
							(mid -0.249642 -0.249642)
							(end -0.2794 -0.1778)
						)
						(arc
							(start -0.2794 0.1778)
							(mid -0.249642 0.249642)
							(end -0.1778 0.2794)
						)
						(arc
							(start 0.1778 0.2794)
							(mid 0.249642 0.249642)
							(end 0.2794 0.1778)
						)
						(arc
							(start 0.2794 -0.1778)
							(mid 0.249642 -0.249642)
							(end 0.1778 -0.2794)
						)
					)
					(width 0)
					(fill yes)
				)
			)
		)
	)
	(footprint ""
		(layer "F.Cu")
		(at 221.1324 -95.6056 -90)
		(property "Reference" "R9804"
			(at 0 0 270)
			(layer "F.SilkS")
			(hide yes)
			(effects
				(font
					(size 1.27 1.27)
				)
			)
		)
		(property "Value" "2K2R5F-GP"
			(at 0 -8.9535 270)
			(unlocked yes)
			(layer "F.Fab")
			(hide yes)
			(effects
				(font
					(size 1.27 1.016)
					(thickness 0.1524)
				)
			)
		)
		(property "Device Type" "R805H24"
			(at 0 -10.6299 270)
			(unlocked yes)
			(layer "F.Fab")
			(hide yes)
			(effects
				(font
					(size 1.27 1.016)
					(thickness 0.1524)
				)
			)
		)
		(duplicate_pad_numbers_are_jumpers no)
		(fp_line
			(start -0.889 1.7018)
			(end 0.889 1.7018)
			(stroke
				(width 0.1524)
				(type default)
			)
			(layer "F.SilkS")
		)
		(fp_line
			(start 0.889 1.7018)
			(end 0.889 -0.508)
			(stroke
				(width 0.1524)
				(type default)
			)
			(layer "F.SilkS")
		)
		(fp_line
			(start -0.889 0.0762)
			(end -0.889 1.7018)
			(stroke
				(width 0.1524)
				(type default)
			)
			(layer "F.SilkS")
		)
		(fp_line
			(start -0.889 -1.7018)
			(end -0.889 0.2794)
			(stroke
				(width 0.1524)
				(type default)
			)
			(layer "F.SilkS")
		)
		(fp_line
			(start 0.889 -1.7018)
			(end 0.889 -0.381)
			(stroke
				(width 0.1524)
				(type default)
			)
			(layer "F.SilkS")
		)
		(fp_line
			(start 0.889 -1.7018)
			(end -0.889 -1.7018)
			(stroke
				(width 0.1524)
				(type default)
			)
			(layer "F.SilkS")
		)
		(fp_poly
			(pts
				(xy 0.9652 -1.778) (xy 0.9652 1.778) (xy -0.9652 1.778) (xy -0.9652 -1.778)
			)
			(stroke
				(width 0)
				(type default)
			)
			(fill no)
			(layer "F.CrtYd")
		)
		(fp_rect
			(start -0.9652 1.778)
			(end 0.9652 -1.778)
			(stroke
				(width 0)
				(type default)
			)
			(fill no)
			(layer "F.Fab")
		)
		(pad "1" smd rect
			(at 0 -0.9652 270)
			(size 1.397 1.143)
			(layers "F.Cu" "F.Mask" "F.Paste")
			(net "P12V_SSD4")
		)
		(pad "2" smd rect
			(at 0 0.9652 270)
			(size 1.397 1.143)
			(layers "F.Cu" "F.Mask" "F.Paste")
			(net "P12V_MOST4_GATE_D")
		)
	)
)
